#ISCELL
  mstr_symbols cad_note *
  *
#ISCELL
  mstr_symbols design_note *
  *
#ISCELL
  mstr_symbols intel_corp_bpage *
  *
#ISCELL
  mstr_standard offpage *
  page191_i1
#ISCELL
  mstr_standard offpage *
  page191_i102
#ISCELL
  mstr_standard offpage *
  page191_i115
#ISCELL
  mstr_standard offpage *
  page191_i118
#ISCELL
  mstr_standard offpage *
  page191_i120
#ISCELL
  mstr_standard offpage *
  page191_i125
#ISCELL
  mstr_standard offpage *
  page191_i127
#ISCELL
  mstr_standard offpage *
  page191_i128
#ISCELL
  mstr_standard offpage *
  page191_i129
#ISCELL
  mstr_standard offpage *
  page191_i132
#ISCELL
  mstr_standard offpage *
  page191_i133
#ISCELL
  mstr_standard offpage *
  page191_i134
#ISCELL
  mstr_standard offpage *
  page191_i135
#ISCELL
  mstr_standard offpage *
  page191_i136
#ISCELL
  mstr_standard offpage *
  page191_i137
#ISCELL
  mstr_standard offpage *
  page191_i139
#ISCELL
  mstr_standard offpage *
  page191_i141
#ISCELL
  mstr_standard offpage *
  page191_i142
#ISCELL
  mstr_standard offpage *
  page191_i143
#ISCELL
  mstr_standard offpage *
  page191_i145
#ISCELL
  mstr_standard offpage *
  page191_i147
#ISCELL
  mstr_standard offpage *
  page191_i148
#ISCELL
  mstr_standard offpage *
  page191_i149
#ISCELL
  mstr_standard offpage *
  page191_i151
#ISCELL
  mstr_standard offpage *
  page191_i156
#ISCELL
  mstr_standard offpage *
  page191_i157
#ISCELL
  mstr_standard offpage *
  page191_i158
#ISCELL
  mstr_standard offpage *
  page191_i160
#ISCELL
  mstr_standard offpage *
  page191_i161
#ISCELL
  mstr_standard offpage *
  page191_i162
#ISCELL
  mstr_standard offpage *
  page191_i163
#ISCELL
  mstr_standard offpage *
  page191_i164
#ISCELL
  mstr_standard offpage *
  page191_i165
#CELL
  mstr_discrete res *
  page191_i166
#ISCELL
  mstr_standard offpage *
  page191_i167
#ISCELL
  mstr_standard offpage *
  page191_i168
#ISCELL
  mstr_standard offpage *
  page191_i169
#ISCELL
  mstr_standard offpage *
  page191_i17
#ISCELL
  mstr_standard offpage *
  page191_i170
#ISCELL
  mstr_symbols p3v3_stby *
  page191_i171
#CELL
  mstr_discrete res *
  page191_i172
#ISCELL
  mstr_standard offpage *
  page191_i173
#ISCELL
  mstr_standard offpage *
  page191_i174
#ISCELL
  mstr_standard offpage *
  page191_i175
#ISCELL
  mstr_standard offpage *
  page191_i176
#ISCELL
  mstr_standard offpage *
  page191_i177
#ISCELL
  mstr_standard offpage *
  page191_i178
#ISCELL
  mstr_standard offpage *
  page191_i179
#ISCELL
  mstr_standard offpage *
  page191_i18
#ISCELL
  mstr_standard offpage *
  page191_i180
#ISCELL
  mstr_standard offpage *
  page191_i181
#ISCELL
  mstr_standard offpage *
  page191_i182
#ISCELL
  mstr_standard offpage *
  page191_i183
#CELL
  mstr_discrete res *
  page191_i184
#ISCELL
  mstr_standard offpage *
  page191_i185
#ISCELL
  mstr_standard offpage *
  page191_i186
#ISCELL
  mstr_standard offpage *
  page191_i187
#ISCELL
  mstr_standard offpage *
  page191_i188
#ISCELL
  mstr_standard offpage *
  page191_i189
#ISCELL
  mstr_standard offpage *
  page191_i19
#ISCELL
  mstr_standard offpage *
  page191_i190
#ISCELL
  mstr_standard offpage *
  page191_i191
#ISCELL
  mstr_standard offpage *
  page191_i192
#CELL
  mstr_discrete res *
  page191_i193
#ISCELL
  mstr_symbols p3v3_stby *
  page191_i194
#CELL
  mstr_discrete res *
  page191_i195
#ISCELL
  mstr_symbols p3v3_stby *
  page191_i196
#CELL
  mstr_discrete res *
  page191_i197
#CELL
  mstr_discrete res *
  page191_i198
#ISCELL
  mstr_standard offpage *
  page191_i199
#ISCELL
  mstr_standard offpage *
  page191_i2
#ISCELL
  mstr_standard offpage *
  page191_i22
#ISCELL
  mstr_standard offpage *
  page191_i24
#ISCELL
  mstr_standard offpage *
  page191_i26
#ISCELL
  mstr_standard offpage *
  page191_i27
#ISCELL
  mstr_standard offpage *
  page191_i33
#ISCELL
  mstr_standard offpage *
  page191_i38
#ISCELL
  mstr_standard offpage *
  page191_i47
#ISCELL
  mstr_standard offpage *
  page191_i49
#CELL
  mstr_memory lcmxo2_a *
  page191_i59
#ISCELL
  mstr_standard offpage *
  page191_i84
#ISCELL
  mstr_standard offpage *
  page191_i87
#ISCELL
  mstr_standard offpage *
  page191_i88
#ISCELL
  mstr_standard offpage *
  page191_i93
#ISCELL
  mstr_standard offpage *
  page191_i95
#ISCELL
  mstr_standard offpage *
  page191_i96
#ISCELL
  mstr_standard offpage *
  page191_i97
#ISCELL
  mstr_standard offpage *
  page191_i99
